# T6G (Grand Teton) — schematic netlist excerpt (pin names and nets, part order shuffled) for the footprints in the layout excerpt that follows; sources: Cadence DE-HDL packaged netlist, KiCad conversion of 04192023_DAF0TMB3IC0_F0TG_MB_C_brd_V02_OCP.brd

R4126  Q_RES  4.7K 5% CHIP  pkg 0402LF  page 125 : A = P3V3_AUX ; B = PRSNT_CABLE_GPU_B3
C603  Q_CAP  0.1UF 10V 10% X7S  pkg C0201  page 290 : A = P1V8_CPU0_RT1_1A ; B = GND
PC588_2  Q_CAP  22UF 16V 20% X6S  pkg C0805  page 198 : A = SW_P12V_AUX_PVDDCR_SOC_P0_FLT ; B = GND

(kicad_pcb
	(version 20260206)
	(generator "pcbnew")
	(generator_version "10.0")
	(general
		(thickness 1.6)
		(legacy_teardrops no)
	)
	(paper "A4")
	(title_block
		(title "04192023_DAF0TMB3IC0_F0TG_MB_C_brd_V02_OCP.brd")
		(comment 1 "Grand Teton / footprints 6975-6977 of 8354")
	)
	(layers
		(0 "F.Cu" signal "TOP")
		(4 "In1.Cu" signal "GND")
		(6 "In2.Cu" signal "IN1")
		(8 "In3.Cu" signal "GND1")
		(10 "In4.Cu" signal "IN2")
		(12 "In5.Cu" signal "GND2")
		(14 "In6.Cu" signal "IN3")
		(16 "In7.Cu" signal "GND3")
		(18 "In8.Cu" signal "VCC")
		(20 "In9.Cu" signal "VCC1")
		(22 "In10.Cu" signal "GND4")
		(24 "In11.Cu" signal "IN4")
		(26 "In12.Cu" signal "GND5")
		(28 "In13.Cu" signal "IN5")
		(30 "In14.Cu" signal "GND6")
		(32 "In15.Cu" signal "IN6")
		(34 "In16.Cu" signal "GND7")
		(2 "B.Cu" signal "BOTTOM")
		(9 "F.Adhes" user "F.Adhesive")
		(11 "B.Adhes" user "B.Adhesive")
		(13 "F.Paste" user "Package Geometry/Pastemask Top")
		(15 "B.Paste" user "Package Geometry/Pastemask Bottom")
		(5 "F.SilkS" user "Ref Des/Silkscreen Top")
		(7 "B.SilkS" user "Ref Des/Silkscreen Bottom")
		(1 "F.Mask" user "Board Geometry/Soldermask Top")
		(3 "B.Mask" user "Board Geometry/Soldermask Bottom")
		(17 "Dwgs.User" user "User.Drawings")
		(19 "Cmts.User" user "User.Comments")
		(21 "Eco1.User" user "User.Eco1")
		(23 "Eco2.User" user "User.Eco2")
		(25 "Edge.Cuts" user "Board Geometry/Outline")
		(27 "Margin" user)
		(31 "F.CrtYd" user "Package Geometry/Place Bound Top")
		(29 "B.CrtYd" user "Package Geometry/Place Bound Bottom")
		(35 "F.Fab" user "Ref Des/Assembly Top")
		(33 "B.Fab" user "Ref Des/Assembly Bottom")
	)
	(footprint ""
		(layer "B.Cu")
		(at 169.686732 -435.851808 90)
		(property "Reference" "R4126"
			(at 0 0 90)
			(layer "B.SilkS")
			(hide yes)
			(effects
				(font
					(size 1.27 1.27)
				)
				(justify mirror)
			)
		)
		(property "Value" ""
			(at 0 0 90)
			(layer "B.Fab")
			(effects
				(font
					(size 1.27 1.27)
				)
				(justify mirror)
			)
		)
		(duplicate_pad_numbers_are_jumpers no)
		(fp_line
			(start 0.7874 -0.4064)
			(end -0.7874 -0.4064)
			(stroke
				(width 0.1524)
				(type default)
			)
			(layer "B.SilkS")
		)
		(fp_line
			(start -0.7874 -0.4064)
			(end -0.7874 0.4064)
			(stroke
				(width 0.1524)
				(type default)
			)
			(layer "B.SilkS")
		)
		(fp_line
			(start 0.7874 0.4064)
			(end 0.7874 -0.4064)
			(stroke
				(width 0.1524)
				(type default)
			)
			(layer "B.SilkS")
		)
		(fp_line
			(start -0.7874 0.4064)
			(end 0.7874 0.4064)
			(stroke
				(width 0.1524)
				(type default)
			)
			(layer "B.SilkS")
		)
		(fp_line
			(start 0.67945 -0.305054)
			(end 0.12065 -0.305054)
			(stroke
				(width 0.1)
				(type default)
			)
			(layer "B.Fab")
		)
		(fp_line
			(start 0.12065 -0.305054)
			(end 0.12065 -0.2794)
			(stroke
				(width 0.1)
				(type default)
			)
			(layer "B.Fab")
		)
		(fp_line
			(start -0.12065 -0.3048)
			(end -0.67945 -0.3048)
			(stroke
				(width 0.1)
				(type default)
			)
			(layer "B.Fab")
		)
		(fp_line
			(start -0.67945 -0.3048)
			(end -0.67945 0.3048)
			(stroke
				(width 0.1)
				(type default)
			)
			(layer "B.Fab")
		)
		(fp_line
			(start 0.12065 -0.2794)
			(end -0.12065 -0.2794)
			(stroke
				(width 0.1)
				(type default)
			)
			(layer "B.Fab")
		)
		(fp_line
			(start -0.12065 -0.2794)
			(end -0.12065 -0.3048)
			(stroke
				(width 0.1)
				(type default)
			)
			(layer "B.Fab")
		)
		(fp_line
			(start 0.12065 0.2794)
			(end 0.12065 0.3048)
			(stroke
				(width 0.1)
				(type default)
			)
			(layer "B.Fab")
		)
		(fp_line
			(start -0.120396 0.2794)
			(end 0.12065 0.2794)
			(stroke
				(width 0.1)
				(type default)
			)
			(layer "B.Fab")
		)
		(fp_line
			(start 0.67945 0.3048)
			(end 0.67945 -0.305054)
			(stroke
				(width 0.1)
				(type default)
			)
			(layer "B.Fab")
		)
		(fp_line
			(start 0.12065 0.3048)
			(end 0.67945 0.3048)
			(stroke
				(width 0.1)
				(type default)
			)
			(layer "B.Fab")
		)
		(fp_line
			(start -0.120396 0.3048)
			(end -0.120396 0.2794)
			(stroke
				(width 0.1)
				(type default)
			)
			(layer "B.Fab")
		)
		(fp_line
			(start -0.67945 0.3048)
			(end -0.120396 0.3048)
			(stroke
				(width 0.1)
				(type default)
			)
			(layer "B.Fab")
		)
		(pad "1" smd circle
			(at 0.40005 0 270)
			(size 0 0)
			(layers "B.Cu" "B.Mask" "B.Paste")
			(net "P3V3_AUX")
		)
		(pad "2" smd circle
			(at -0.40005 0 270)
			(size 0 0)
			(layers "B.Cu" "B.Mask" "B.Paste")
			(net "PRSNT_CABLE_GPU_B3")
		)
	)
	(footprint ""
		(layer "B.Cu")
		(at 344.306144 -395.148562 90)
		(property "Reference" "C603"
			(at 0 0 90)
			(layer "B.SilkS")
			(hide yes)
			(effects
				(font
					(size 1.27 1.27)
				)
				(justify mirror)
			)
		)
		(property "Value" ""
			(at 0 0 90)
			(layer "B.Fab")
			(effects
				(font
					(size 1.27 1.27)
				)
				(justify mirror)
			)
		)
		(duplicate_pad_numbers_are_jumpers no)
		(fp_line
			(start 0.299974 -0.150114)
			(end -0.299974 -0.150114)
			(stroke
				(width 0.1)
				(type default)
			)
			(layer "B.Fab")
		)
		(fp_line
			(start -0.299974 -0.150114)
			(end -0.299974 0.150114)
			(stroke
				(width 0.1)
				(type default)
			)
			(layer "B.Fab")
		)
		(fp_line
			(start 0.299974 0.150114)
			(end 0.299974 -0.150114)
			(stroke
				(width 0.1)
				(type default)
			)
			(layer "B.Fab")
		)
		(fp_line
			(start -0.299974 0.150114)
			(end 0.299974 0.150114)
			(stroke
				(width 0.1)
				(type default)
			)
			(layer "B.Fab")
		)
		(pad "1" smd rect
			(at 0.2667 0 270)
			(size 0.3048 0.381)
			(layers "B.Cu" "B.Mask" "B.Paste")
			(net "P1V8_CPU0_RT1_1A")
		)
		(pad "2" smd rect
			(at -0.2667 0 270)
			(size 0.3048 0.381)
			(layers "B.Cu" "B.Mask" "B.Paste")
			(net "GND")
		)
	)
	(footprint ""
		(layer "B.Cu")
		(at 404.922736 -164.804852 90)
		(property "Reference" "PC588_2"
			(at 0 0 90)
			(layer "B.SilkS")
			(hide yes)
			(effects
				(font
					(size 1.27 1.27)
				)
				(justify mirror)
			)
		)
		(property "Value" ""
			(at 0 0 90)
			(layer "B.Fab")
			(effects
				(font
					(size 1.27 1.27)
				)
				(justify mirror)
			)
		)
		(duplicate_pad_numbers_are_jumpers no)
		(fp_line
			(start 1.524 -0.762)
			(end -1.524 -0.762)
			(stroke
				(width 0.1524)
				(type default)
			)
			(layer "B.SilkS")
		)
		(fp_line
			(start -1.524 -0.762)
			(end -1.524 0.762)
			(stroke
				(width 0.1524)
				(type default)
			)
			(layer "B.SilkS")
		)
		(fp_line
			(start 1.524 0.762)
			(end 1.524 -0.762)
			(stroke
				(width 0.1524)
				(type default)
			)
			(layer "B.SilkS")
		)
		(fp_line
			(start -1.524 0.762)
			(end 1.524 0.762)
			(stroke
				(width 0.1524)
				(type default)
			)
			(layer "B.SilkS")
		)
		(fp_line
			(start 1.1049 -0.724916)
			(end 1.1049 0.724916)
			(stroke
				(width 0.1)
				(type default)
			)
			(layer "B.Fab")
		)
		(fp_line
			(start -1.1049 -0.724916)
			(end 1.1049 -0.724916)
			(stroke
				(width 0.1)
				(type default)
			)
			(layer "B.Fab")
		)
		(fp_line
			(start 1.1049 0.724916)
			(end -1.1049 0.724916)
			(stroke
				(width 0.1)
				(type default)
			)
			(layer "B.Fab")
		)
		(fp_line
			(start -1.1049 0.724916)
			(end -1.1049 -0.724916)
			(stroke
				(width 0.1)
				(type default)
			)
			(layer "B.Fab")
		)
		(pad "1" smd rect
			(at 0.889 0 90)
			(size 1.016 1.27)
			(layers "B.Cu" "B.Mask" "B.Paste")
			(net "SW_P12V_AUX_PVDDCR_SOC_P0_FLT")
		)
		(pad "2" smd rect
			(at -0.889 0 90)
			(size 1.016 1.27)
			(layers "B.Cu" "B.Mask" "B.Paste")
			(net "GND")
		)
	)
)
